# TIMECARD (Time Appliance Project (Time Card)) — schematic netlist excerpt (pin names and nets, part order shuffled) for the footprints in the layout excerpt that follows; sources: Cadence DE-HDL packaged netlist, KiCad conversion of R4006-B0001-02_R01.brd

C5  CAPACITOR  0.1UF 25V 10%  pkg SMC_0402R_H022  page 27 : \1\ = XP12R0V_A_SS ; \2\ = SG
TP140  TP_PIONT  pkg TP010CT020B030_PTH  page 25 : \1\ = IO_L24P_34
C292  CAPACITOR  22UF 10V 20%  pkg SMC_0805R_H057  page 14 : \1\ = XP2R5V_FPGA ; \2\ = SG

(kicad_pcb
	(version 20260206)
	(generator "pcbnew")
	(generator_version "10.0")
	(general
		(thickness 1.6)
		(legacy_teardrops no)
	)
	(paper "A4")
	(title_block
		(title "timecard-production-celestica-r4006 — R4006-B0001-02_R01.brd")
		(comment 1 "Time Appliance Project (Time Card) / footprints 349-351 of 1113")
	)
	(layers
		(0 "F.Cu" signal "TOP")
		(4 "In1.Cu" signal "L02_GND1")
		(6 "In2.Cu" signal "L03_SIG1")
		(8 "In3.Cu" signal "L04_GND2")
		(10 "In4.Cu" signal "L05_VCC1")
		(12 "In5.Cu" signal "L06_VCC2")
		(14 "In6.Cu" signal "L07_GND3")
		(16 "In7.Cu" signal "L08_SIG2")
		(18 "In8.Cu" signal "L09_GND4")
		(2 "B.Cu" signal "BOTTOM")
		(9 "F.Adhes" user "F.Adhesive")
		(11 "B.Adhes" user "B.Adhesive")
		(13 "F.Paste" user "Package Geometry/Pastemask Top")
		(15 "B.Paste" user "Package Geometry/Pastemask Bottom")
		(5 "F.SilkS" user "Ref Des/Silkscreen Top")
		(7 "B.SilkS" user "Ref Des/Silkscreen Bottom")
		(1 "F.Mask" user "Board Geometry/Soldermask Top")
		(3 "B.Mask" user "Board Geometry/Soldermask Bottom")
		(17 "Dwgs.User" user "User.Drawings")
		(19 "Cmts.User" user "User.Comments")
		(21 "Eco1.User" user "User.Eco1")
		(23 "Eco2.User" user "User.Eco2")
		(25 "Edge.Cuts" user "Board Geometry/Outline")
		(27 "Margin" user)
		(31 "F.CrtYd" user "Package Geometry/Place Bound Top")
		(29 "B.CrtYd" user "Package Geometry/Place Bound Bottom")
		(35 "F.Fab" user "Ref Des/Assembly Top")
		(33 "B.Fab" user "Ref Des/Assembly Bottom")
	)
	(footprint ""
		(layer "F.Cu")
		(at 117.346984 -41.32326)
		(property "Reference" "TP140"
			(at 0 0 0)
			(layer "F.SilkS")
			(hide yes)
			(effects
				(font
					(size 1.27 1.27)
				)
			)
		)
		(property "Value" ""
			(at 0 0 0)
			(layer "F.Fab")
			(effects
				(font
					(size 1.27 1.27)
				)
			)
		)
		(property "Device Type" "TP_PIONT-TP010CT020B030_PTH-TPA"
			(at -1.341882 0.996696 0)
			(unlocked yes)
			(layer "F.Fab")
			(hide yes)
			(effects
				(font
					(size 0.7874 0.5842)
					(thickness 0.1524)
				)
				(justify left)
			)
		)
		(duplicate_pad_numbers_are_jumpers no)
		(fp_poly
			(pts
				(arc
					(start 0.889 0)
					(mid -0.889 0)
					(end 0.889 0)
				)
			)
			(stroke
				(width 0)
				(type default)
			)
			(fill no)
			(layer "B.CrtYd")
		)
		(fp_poly
			(pts
				(arc
					(start 0.889 0)
					(mid -0.889 0)
					(end 0.889 0)
				)
			)
			(stroke
				(width 0)
				(type default)
			)
			(fill no)
			(layer "F.CrtYd")
		)
		(pad "1" thru_hole circle
			(at 0 0)
			(size 0.508 0.508)
			(drill 0.254)
			(layers "*.Cu" "*.Mask")
			(remove_unused_layers no)
			(net "IO_L24P_34")
			(clearance 0.1016)
			(padstack
				(mode front_inner_back)
				(layer "Inner"
					(shape circle)
					(size 0.508 0.508)
					(clearance 0.1016)
				)
				(layer "B.Cu"
					(shape circle)
					(size 0.762 0.762)
					(clearance -0.0254)
				)
			)
		)
	)
	(footprint ""
		(layer "F.Cu")
		(at 145.8214 -96.6978)
		(property "Reference" "C5"
			(at 2.667 -0.59563 0)
			(unlocked yes)
			(layer "F.SilkS")
			(effects
				(font
					(size 0.7874 0.5842)
					(thickness 0.1524)
				)
			)
		)
		(property "Value" "VAL*"
			(at 0.0762 2.067306 0)
			(unlocked yes)
			(layer "F.Fab")
			(hide yes)
			(effects
				(font
					(size 0.7874 0.5842)
					(thickness 0.1524)
				)
			)
		)
		(property "Device Type" "CAPACITOR-G105-0B104-EK,0.1UF,A"
			(at 0.0508 1.127506 0)
			(unlocked yes)
			(layer "F.Fab")
			(hide yes)
			(effects
				(font
					(size 0.7874 0.5842)
					(thickness 0.1524)
				)
			)
		)
		(property "User Part Number" "PARTNUM*"
			(at 0.1016 4.023106 0)
			(unlocked yes)
			(layer "Cmts.User")
			(hide yes)
			(effects
				(font
					(size 0.7874 0.5842)
					(thickness 0.1524)
				)
			)
		)
		(property "Tolerance" "TOL*"
			(at 0.0762 3.032506 0)
			(unlocked yes)
			(layer "Cmts.User")
			(hide yes)
			(effects
				(font
					(size 0.7874 0.5842)
					(thickness 0.1524)
				)
			)
		)
		(duplicate_pad_numbers_are_jumpers no)
		(fp_line
			(start -1.143 -0.5588)
			(end -1.143 0.5588)
			(stroke
				(width 0.1)
				(type default)
			)
			(layer "F.SilkS")
		)
		(fp_line
			(start -1.143 0.5588)
			(end 1.143 0.5588)
			(stroke
				(width 0.1)
				(type default)
			)
			(layer "F.SilkS")
		)
		(fp_line
			(start 1.143 -0.5588)
			(end -1.143 -0.5588)
			(stroke
				(width 0.1)
				(type default)
			)
			(layer "F.SilkS")
		)
		(fp_line
			(start 1.143 0.5588)
			(end 1.143 -0.5588)
			(stroke
				(width 0.1)
				(type default)
			)
			(layer "F.SilkS")
		)
		(fp_rect
			(start -1.143 0.5588)
			(end 1.143 -0.5588)
			(stroke
				(width 0)
				(type default)
			)
			(fill no)
			(layer "F.CrtYd")
		)
		(fp_line
			(start -0.508 -0.3048)
			(end -0.508 0.3048)
			(stroke
				(width 0.1)
				(type default)
			)
			(layer "F.Fab")
		)
		(fp_line
			(start -0.508 0.3048)
			(end 0.508 0.3048)
			(stroke
				(width 0.1)
				(type default)
			)
			(layer "F.Fab")
		)
		(fp_line
			(start 0.508 -0.3048)
			(end -0.508 -0.3048)
			(stroke
				(width 0.1)
				(type default)
			)
			(layer "F.Fab")
		)
		(fp_line
			(start 0.508 0.3048)
			(end 0.508 -0.3048)
			(stroke
				(width 0.1)
				(type default)
			)
			(layer "F.Fab")
		)
		(pad "1" smd rect
			(at -0.5334 0)
			(size 0.7112 0.6096)
			(layers "F.Cu" "F.Mask" "F.Paste")
			(net "XP12R0V_A_SS")
		)
		(pad "2" smd rect
			(at 0.5334 0)
			(size 0.7112 0.6096)
			(layers "F.Cu" "F.Mask" "F.Paste")
			(net "SG")
		)
		(zone
			(layer "F.Cu")
			(hatch none 0.5)
			(connect_pads
				(clearance 0)
			)
			(min_thickness 0.25)
			(keepout
				(tracks allowed)
				(vias not_allowed)
				(pads allowed)
				(copperpour not_allowed)
				(footprints allowed)
			)
			(placement
				(enabled no)
				(sheetname "")
			)
			(fill
				(thermal_gap 0.5)
				(thermal_bridge_width 0.5)
				(island_removal_mode 0)
			)
			(polygon
				(pts
					(xy 145.7452 -96.393) (xy 145.8976 -96.393) (xy 145.8976 -97.0026) (xy 145.7452 -97.0026)
				)
			)
		)
	)
	(footprint ""
		(layer "F.Cu")
		(at 126.1364 -32.1056 180)
		(property "Reference" "C292"
			(at 0 -1.96977 0)
			(unlocked yes)
			(layer "F.SilkS")
			(effects
				(font
					(size 0.7874 0.5842)
					(thickness 0.1524)
				)
			)
		)
		(property "Value" "VAL*"
			(at 0.0762 3.134106 180)
			(unlocked yes)
			(layer "F.Fab")
			(hide yes)
			(effects
				(font
					(size 0.7874 0.5842)
					(thickness 0.1524)
				)
			)
		)
		(property "Tolerance" "TOL*"
			(at 0.0762 4.048506 180)
			(unlocked yes)
			(layer "Cmts.User")
			(hide yes)
			(effects
				(font
					(size 0.7874 0.5842)
					(thickness 0.1524)
				)
			)
		)
		(property "User Part Number" "PARTNUM*"
			(at 0.1016 5.013706 180)
			(unlocked yes)
			(layer "Cmts.User")
			(hide yes)
			(effects
				(font
					(size 0.7874 0.5842)
					(thickness 0.1524)
				)
			)
		)
		(property "Device Type" "CAPACITOR-G107-0F226-CM,22UF,2A"
			(at 0.0508 2.194306 180)
			(unlocked yes)
			(layer "F.Fab")
			(hide yes)
			(effects
				(font
					(size 0.7874 0.5842)
					(thickness 0.1524)
				)
			)
		)
		(duplicate_pad_numbers_are_jumpers no)
		(fp_line
			(start 1.5748 0.9398)
			(end 1.5748 -0.9398)
			(stroke
				(width 0.1)
				(type default)
			)
			(layer "F.SilkS")
		)
		(fp_line
			(start 1.5748 -0.9398)
			(end -1.5748 -0.9398)
			(stroke
				(width 0.1)
				(type default)
			)
			(layer "F.SilkS")
		)
		(fp_line
			(start -1.5748 0.9398)
			(end 1.5748 0.9398)
			(stroke
				(width 0.1)
				(type default)
			)
			(layer "F.SilkS")
		)
		(fp_line
			(start -1.5748 -0.9398)
			(end -1.5748 0.9398)
			(stroke
				(width 0.1)
				(type default)
			)
			(layer "F.SilkS")
		)
		(fp_rect
			(start 1.5748 0.9398)
			(end -1.5748 -0.9398)
			(stroke
				(width 0)
				(type default)
			)
			(fill no)
			(layer "F.CrtYd")
		)
		(fp_line
			(start 1.016 0.635)
			(end 1.016 -0.635)
			(stroke
				(width 0.1)
				(type default)
			)
			(layer "F.Fab")
		)
		(fp_line
			(start 1.016 -0.635)
			(end -1.016 -0.635)
			(stroke
				(width 0.1)
				(type default)
			)
			(layer "F.Fab")
		)
		(fp_line
			(start -1.016 0.635)
			(end 1.016 0.635)
			(stroke
				(width 0.1)
				(type default)
			)
			(layer "F.Fab")
		)
		(fp_line
			(start -1.016 -0.635)
			(end -1.016 0.635)
			(stroke
				(width 0.1)
				(type default)
			)
			(layer "F.Fab")
		)
		(pad "1" smd rect
			(at -0.8382 0 180)
			(size 0.9652 1.3716)
			(layers "F.Cu" "F.Mask" "F.Paste")
			(net "XP2R5V_FPGA")
		)
		(pad "2" smd rect
			(at 0.8382 0 180)
			(size 0.9652 1.3716)
			(layers "F.Cu" "F.Mask" "F.Paste")
			(net "SG")
		)
		(zone
			(layer "F.Cu")
			(hatch none 0.5)
			(connect_pads
				(clearance 0)
			)
			(min_thickness 0.25)
			(keepout
				(tracks not_allowed)
				(vias allowed)
				(pads allowed)
				(copperpour not_allowed)
				(footprints allowed)
			)
			(placement
				(enabled no)
				(sheetname "")
			)
			(fill
				(thermal_gap 0.5)
				(thermal_bridge_width 0.5)
				(island_removal_mode 0)
			)
			(polygon
				(pts
					(xy 125.9078 -32.7406) (xy 125.9078 -31.4706) (xy 126.365 -31.4706) (xy 126.365 -32.7406)
				)
			)
		)
		(zone
			(layer "F.Cu")
			(hatch none 0.5)
			(connect_pads
				(clearance 0)
			)
			(min_thickness 0.25)
			(keepout
				(tracks allowed)
				(vias not_allowed)
				(pads allowed)
				(copperpour not_allowed)
				(footprints allowed)
			)
			(placement
				(enabled no)
				(sheetname "")
			)
			(fill
				(thermal_gap 0.5)
				(thermal_bridge_width 0.5)
				(island_removal_mode 0)
			)
			(polygon
				(pts
					(xy 125.9078 -32.7406) (xy 125.9078 -31.4706) (xy 126.365 -31.4706) (xy 126.365 -32.7406)
				)
			)
		)
	)
)
